(kicad_pcb
	(version 20241229)
	(generator "pcbnew")
	(generator_version "9.0")
	(general
		(thickness 1.711)
		(legacy_teardrops no)
	)
	(paper "A4")
	(title_block
		(title "Antmicro Baseboard for Jetson AGX Thor")
		(date "2026-02-18")
		(rev "1.1.0")
		(company "Antmicro Ltd")
		(comment 1 "www.antmicro.com")
		(comment 9 "footprint 1149 of 1170 (J13), pads 1-71 of 71")
	)
	(layers
		(0 "F.Cu" signal)
		(4 "In1.Cu" signal)
		(6 "In2.Cu" signal)
		(8 "In3.Cu" signal)
		(10 "In4.Cu" jumper)
		(12 "In5.Cu" signal)
		(14 "In6.Cu" signal)
		(16 "In7.Cu" signal)
		(18 "In8.Cu" signal)
		(2 "B.Cu" signal)
		(9 "F.Adhes" user "F.Adhesive")
		(11 "B.Adhes" user "B.Adhesive")
		(13 "F.Paste" user)
		(15 "B.Paste" user)
		(5 "F.SilkS" user "F.Silkscreen")
		(7 "B.SilkS" user "B.Silkscreen")
		(1 "F.Mask" user)
		(3 "B.Mask" user)
		(17 "Dwgs.User" user "User.Drawings")
		(19 "Cmts.User" user "User.Comments")
		(21 "Eco1.User" user "User.Eco1")
		(23 "Eco2.User" user "User.Eco2")
		(25 "Edge.Cuts" user)
		(27 "Margin" user)
		(31 "F.CrtYd" user "F.Courtyard")
		(29 "B.CrtYd" user "B.Courtyard")
		(35 "F.Fab" user)
		(33 "B.Fab" user)
	)
	(footprint "antmicro-footprints:Bus_M.2_Socket_Key_M_TE_1-2199230-6"
		(locked yes)
		(layer "B.Cu")
		(at 117.46 104.501 -90)
		(property "Reference" "J13"
			(at 4.83 -5.49 90)
			(layer "B.SilkS")
			(effects
				(font
					(size 0.7 0.7)
					(thickness 0.15)
				)
				(justify right top mirror)
			)
		)
		(property "Value" "Bus_M.2_1-2199230-6"
			(at -11.25 -6.124 90)
			(layer "B.Fab")
			(effects
				(font
					(size 0.7 0.7)
					(thickness 0.15)
				)
				(justify left bottom mirror)
			)
		)
		(property "Datasheet" "https://www.te.com/commerce/DocumentDelivery/DDEController?Action=srchrtrv&DocNm=2199230&DocType=Customer+Drawing&DocLang=English"
			(at 0 0 90)
			(layer "B.Fab")
			(hide yes)
			(effects
				(font
					(size 1.27 1.27)
					(thickness 0.15)
				)
				(justify mirror)
			)
		)
		(property "Description" "Key M Card Edge Connector, 0, Dual Side, 67 Contacts, Surface Mount, Right Angle, Solder"
			(at 0 0 90)
			(layer "B.Fab")
			(hide yes)
			(effects
				(font
					(size 1.27 1.27)
					(thickness 0.15)
				)
				(justify mirror)
			)
		)
		(property "Manufacturer" "TE Connectivity"
			(at 0 0 90)
			(unlocked yes)
			(layer "B.Fab")
			(hide yes)
			(effects
				(font
					(size 1 1)
					(thickness 0.15)
				)
				(justify mirror)
			)
		)
		(property "MPN" "1-2199230-6"
			(at 0 0 90)
			(unlocked yes)
			(layer "B.Fab")
			(hide yes)
			(effects
				(font
					(size 1 1)
					(thickness 0.15)
				)
				(justify mirror)
			)
		)
		(property "Author" "Antmicro"
			(at 0 0 90)
			(unlocked yes)
			(layer "B.Fab")
			(hide yes)
			(effects
				(font
					(size 1 1)
					(thickness 0.15)
				)
				(justify mirror)
			)
		)
		(property "License" "Apache-2.0"
			(at 0 0 90)
			(unlocked yes)
			(layer "B.Fab")
			(hide yes)
			(effects
				(font
					(size 1 1)
					(thickness 0.15)
				)
				(justify mirror)
			)
		)
		(sheetname "/M.2/")
		(sheetfile "m2.kicad_sch")
		(attr smd)
		(pad "" np_thru_hole circle
			(at -10 -1.499 270)
			(size 1.1 1.1)
			(drill 1.1)
			(layers "*.Mask")
		)
		(pad "" np_thru_hole circle
			(at 9.997 -1.499 270)
			(size 1.6 1.6)
			(drill 1.6)
			(layers "*.Mask")
		)
		(pad "1" smd rect
			(at -9.25 3.775 270)
			(size 0.3 1.55)
			(layers "B.Cu" "B.Mask" "B.Paste")
			(net 1 "GND")
			(pinfunction "GND")
			(pintype "power_in")
		)
		(pad "2" smd rect
			(at -9.003 -3.773 270)
			(size 0.3 1.55)
			(layers "B.Cu" "B.Mask" "B.Paste")
			(net 14 "/M.2/3V3_M2")
			(pinfunction "3V3")
			(pintype "passive")
		)
		(pad "3" smd rect
			(at -8.753 3.775 270)
			(size 0.3 1.55)
			(layers "B.Cu" "B.Mask" "B.Paste")
			(net 1 "GND")
			(pinfunction "GND")
			(pintype "passive")
		)
		(pad "4" smd rect
			(at -8.503 -3.773 270)
			(size 0.3 1.55)
			(layers "B.Cu" "B.Mask" "B.Paste")
			(net 14 "/M.2/3V3_M2")
			(pinfunction "3V3")
			(pintype "passive")
		)
		(pad "5" smd rect
			(at -8.253 3.775 270)
			(size 0.3 1.55)
			(layers "B.Cu" "B.Mask" "B.Paste")
			(net 564 "/M.2/PCIe_{C5x4}.RX3-")
			(pinfunction "PER3_N")
			(pintype "output")
		)
		(pad "6" smd rect
			(at -8.001 -3.773 270)
			(size 0.3 1.55)
			(layers "B.Cu" "B.Mask" "B.Paste")
			(net 226 "unconnected-(J13-NC-Pad6)")
			(pinfunction "NC")
			(pintype "no_connect")
		)
		(pad "7" smd rect
			(at -7.752 3.775 270)
			(size 0.3 1.55)
			(layers "B.Cu" "B.Mask" "B.Paste")
			(net 681 "/M.2/PCIe_{C5x4}.RX3+")
			(pinfunction "PER3_P")
			(pintype "output")
		)
		(pad "8" smd rect
			(at -7.502 -3.773 270)
			(size 0.3 1.55)
			(layers "B.Cu" "B.Mask" "B.Paste")
			(net 223 "unconnected-(J13-NC-Pad8)")
			(pinfunction "NC")
			(pintype "no_connect")
		)
		(pad "9" smd rect
			(at -7.252 3.775 270)
			(size 0.3 1.55)
			(layers "B.Cu" "B.Mask" "B.Paste")
			(net 1 "GND")
			(pinfunction "GND")
			(pintype "passive")
		)
		(pad "10" smd rect
			(at -7.002 -3.773 270)
			(size 0.3 1.55)
			(layers "B.Cu" "B.Mask" "B.Paste")
			(net 33 "Net-(D32-C)")
			(pinfunction "LED")
			(pintype "passive")
		)
		(pad "11" smd rect
			(at -6.752 3.775 270)
			(size 0.3 1.55)
			(layers "B.Cu" "B.Mask" "B.Paste")
			(net 436 "/M.2/M2_M_PET3_N")
			(pinfunction "PET3_N")
			(pintype "input")
		)
		(pad "12" smd rect
			(at -6.502 -3.773 270)
			(size 0.3 1.55)
			(layers "B.Cu" "B.Mask" "B.Paste")
			(net 14 "/M.2/3V3_M2")
			(pinfunction "3V3")
			(pintype "passive")
		)
		(pad "13" smd rect
			(at -6.252 3.775 270)
			(size 0.3 1.55)
			(layers "B.Cu" "B.Mask" "B.Paste")
			(net 408 "/M.2/M2_M_PET3_P")
			(pinfunction "PET3_P")
			(pintype "input")
		)
		(pad "14" smd rect
			(at -6.002 -3.773 270)
			(size 0.3 1.55)
			(layers "B.Cu" "B.Mask" "B.Paste")
			(net 14 "/M.2/3V3_M2")
			(pinfunction "3V3")
			(pintype "passive")
		)
		(pad "15" smd rect
			(at -5.752 3.775 270)
			(size 0.3 1.55)
			(layers "B.Cu" "B.Mask" "B.Paste")
			(net 1 "GND")
			(pinfunction "GND")
			(pintype "passive")
		)
		(pad "16" smd rect
			(at -5.502 -3.773 270)
			(size 0.3 1.55)
			(layers "B.Cu" "B.Mask" "B.Paste")
			(net 14 "/M.2/3V3_M2")
			(pinfunction "3V3")
			(pintype "passive")
		)
		(pad "17" smd rect
			(at -5.252 3.775 270)
			(size 0.3 1.55)
			(layers "B.Cu" "B.Mask" "B.Paste")
			(net 731 "/M.2/PCIe_{C5x4}.RX2+")
			(pinfunction "PER2_N")
			(pintype "output")
		)
		(pad "18" smd rect
			(at -5.002 -3.773 270)
			(size 0.3 1.55)
			(layers "B.Cu" "B.Mask" "B.Paste")
			(net 14 "/M.2/3V3_M2")
			(pinfunction "3V3")
			(pintype "passive")
		)
		(pad "19" smd rect
			(at -4.752 3.775 270)
			(size 0.3 1.55)
			(layers "B.Cu" "B.Mask" "B.Paste")
			(net 552 "/M.2/PCIe_{C5x4}.RX2-")
			(pinfunction "PER2_P")
			(pintype "output")
		)
		(pad "20" smd rect
			(at -4.502 -3.773 270)
			(size 0.3 1.55)
			(layers "B.Cu" "B.Mask" "B.Paste")
			(net 232 "unconnected-(J13-NC-Pad20)")
			(pinfunction "NC")
			(pintype "no_connect")
		)
		(pad "21" smd rect
			(at -4.252 3.775 270)
			(size 0.3 1.55)
			(layers "B.Cu" "B.Mask" "B.Paste")
			(net 1 "GND")
			(pinfunction "GND")
			(pintype "passive")
		)
		(pad "22" smd rect
			(at -4.002 -3.773 270)
			(size 0.3 1.55)
			(layers "B.Cu" "B.Mask" "B.Paste")
			(net 216 "unconnected-(J13-NC-Pad22)")
			(pinfunction "NC")
			(pintype "no_connect")
		)
		(pad "23" smd rect
			(at -3.751 3.775 270)
			(size 0.3 1.55)
			(layers "B.Cu" "B.Mask" "B.Paste")
			(net 399 "/M.2/M2_M_PET2_P")
			(pinfunction "PET2_N")
			(pintype "input")
		)
		(pad "24" smd rect
			(at -3.501 -3.773 270)
			(size 0.3 1.55)
			(layers "B.Cu" "B.Mask" "B.Paste")
			(net 218 "unconnected-(J13-NC-Pad24)")
			(pinfunction "NC")
			(pintype "no_connect")
		)
		(pad "25" smd rect
			(at -3.251 3.775 270)
			(size 0.3 1.55)
			(layers "B.Cu" "B.Mask" "B.Paste")
			(net 423 "/M.2/M2_M_PET2_N")
			(pinfunction "PET2_P")
			(pintype "input")
		)
		(pad "26" smd rect
			(at -3.001 -3.773 270)
			(size 0.3 1.55)
			(layers "B.Cu" "B.Mask" "B.Paste")
			(net 230 "unconnected-(J13-NC-Pad26)")
			(pinfunction "NC")
			(pintype "no_connect")
		)
		(pad "27" smd rect
			(at -2.751 3.775 270)
			(size 0.3 1.55)
			(layers "B.Cu" "B.Mask" "B.Paste")
			(net 1 "GND")
			(pinfunction "GND")
			(pintype "passive")
		)
		(pad "28" smd rect
			(at -2.501 -3.773 270)
			(size 0.3 1.55)
			(layers "B.Cu" "B.Mask" "B.Paste")
			(net 222 "unconnected-(J13-NC-Pad28)")
			(pinfunction "NC")
			(pintype "no_connect")
		)
		(pad "29" smd rect
			(at -2.251 3.775 270)
			(size 0.3 1.55)
			(layers "B.Cu" "B.Mask" "B.Paste")
			(net 674 "/M.2/PCIe_{C5x4}.RX1+")
			(pinfunction "PER1_N")
			(pintype "output")
		)
		(pad "30" smd rect
			(at -2.001 -3.773 270)
			(size 0.3 1.55)
			(layers "B.Cu" "B.Mask" "B.Paste")
			(net 228 "unconnected-(J13-NC-Pad30)")
			(pinfunction "NC")
			(pintype "no_connect")
		)
		(pad "31" smd rect
			(at -1.752 3.775 270)
			(size 0.3 1.55)
			(layers "B.Cu" "B.Mask" "B.Paste")
			(net 620 "/M.2/PCIe_{C5x4}.RX1-")
			(pinfunction "PER1_P")
			(pintype "output")
		)
		(pad "32" smd rect
			(at -1.502 -3.773 270)
			(size 0.3 1.55)
			(layers "B.Cu" "B.Mask" "B.Paste")
			(net 229 "unconnected-(J13-NC-Pad32)")
			(pinfunction "NC")
			(pintype "no_connect")
		)
		(pad "33" smd rect
			(at -1.252 3.775 270)
			(size 0.3 1.55)
			(layers "B.Cu" "B.Mask" "B.Paste")
			(net 1 "GND")
			(pinfunction "GND")
			(pintype "passive")
		)
		(pad "34" smd rect
			(at -1.002 -3.773 270)
			(size 0.3 1.55)
			(layers "B.Cu" "B.Mask" "B.Paste")
			(net 227 "unconnected-(J13-NC-Pad34)")
			(pinfunction "NC")
			(pintype "no_connect")
		)
		(pad "35" smd rect
			(at -0.751 3.775 270)
			(size 0.3 1.55)
			(layers "B.Cu" "B.Mask" "B.Paste")
			(net 391 "/M.2/M2_M_PET1_P")
			(pinfunction "PET1_N")
			(pintype "input")
		)
		(pad "36" smd rect
			(at -0.501 -3.773 270)
			(size 0.3 1.55)
			(layers "B.Cu" "B.Mask" "B.Paste")
			(net 219 "unconnected-(J13-NC-Pad36)")
			(pinfunction "NC")
			(pintype "no_connect")
		)
		(pad "37" smd rect
			(at -0.251 3.775 270)
			(size 0.3 1.55)
			(layers "B.Cu" "B.Mask" "B.Paste")
			(net 417 "/M.2/M2_M_PET1_N")
			(pinfunction "PET1_P")
			(pintype "input")
		)
		(pad "38" smd rect
			(at -0.001 -3.773 270)
			(size 0.3 1.55)
			(layers "B.Cu" "B.Mask" "B.Paste")
			(net 233 "unconnected-(J13-NC-Pad38)")
			(pinfunction "NC")
			(pintype "no_connect")
		)
		(pad "39" smd rect
			(at 0.248 3.775 270)
			(size 0.3 1.55)
			(layers "B.Cu" "B.Mask" "B.Paste")
			(net 1 "GND")
			(pinfunction "GND")
			(pintype "passive")
		)
		(pad "40" smd rect
			(at 0.498 -3.773 270)
			(size 0.3 1.55)
			(layers "B.Cu" "B.Mask" "B.Paste")
			(net 235 "/M.2/M2_M_SMB_CLK")
			(pinfunction "SMB_CLK")
			(pintype "input")
		)
		(pad "41" smd rect
			(at 0.748 3.775 270)
			(size 0.3 1.55)
			(layers "B.Cu" "B.Mask" "B.Paste")
			(net 669 "/M.2/PCIe_{C5x4}.RX0-")
			(pinfunction "PER0_N")
			(pintype "output")
		)
		(pad "42" smd rect
			(at 0.998 -3.773 270)
			(size 0.3 1.55)
			(layers "B.Cu" "B.Mask" "B.Paste")
			(net 217 "/M.2/M2_M_SMB_DATA")
			(pinfunction "SMB_DATA")
			(pintype "bidirectional")
		)
		(pad "43" smd rect
			(at 1.249 3.775 270)
			(size 0.3 1.55)
			(layers "B.Cu" "B.Mask" "B.Paste")
			(net 725 "/M.2/PCIe_{C5x4}.RX0+")
			(pinfunction "PER0_P")
			(pintype "output")
		)
		(pad "44" smd rect
			(at 1.499 -3.773 270)
			(size 0.3 1.55)
			(layers "B.Cu" "B.Mask" "B.Paste")
			(net 236 "/M.2/~{M2_M_ALERT}")
			(pinfunction "ALERT")
			(pintype "output")
		)
		(pad "45" smd rect
			(at 1.749 3.775 270)
			(size 0.3 1.55)
			(layers "B.Cu" "B.Mask" "B.Paste")
			(net 1 "GND")
			(pinfunction "GND")
			(pintype "passive")
		)
		(pad "46" smd rect
			(at 1.999 -3.773 270)
			(size 0.3 1.55)
			(layers "B.Cu" "B.Mask" "B.Paste")
			(net 238 "unconnected-(J13-NC-Pad46)")
			(pinfunction "NC")
			(pintype "no_connect")
		)
		(pad "47" smd rect
			(at 2.249 3.775 270)
			(size 0.3 1.55)
			(layers "B.Cu" "B.Mask" "B.Paste")
			(net 415 "/M.2/M2_M_PET0_N")
			(pinfunction "PET0_N")
			(pintype "input")
		)
		(pad "48" smd rect
			(at 2.499 -3.773 270)
			(size 0.3 1.55)
			(layers "B.Cu" "B.Mask" "B.Paste")
			(net 225 "unconnected-(J13-NC-Pad48)")
			(pinfunction "NC")
			(pintype "no_connect")
		)
		(pad "49" smd rect
			(at 2.749 3.775 270)
			(size 0.3 1.55)
			(layers "B.Cu" "B.Mask" "B.Paste")
			(net 386 "/M.2/M2_M_PET0_P")
			(pinfunction "PET0_P")
			(pintype "input")
		)
		(pad "50" smd rect
			(at 2.999 -3.773 270)
			(size 0.3 1.55)
			(layers "B.Cu" "B.Mask" "B.Paste")
			(net 827 "/M.2/~{PERST_M}")
			(pinfunction "~{PERST}")
			(pintype "input")
		)
		(pad "51" smd rect
			(at 3.249 3.775 270)
			(size 0.3 1.55)
			(layers "B.Cu" "B.Mask" "B.Paste")
			(net 1 "GND")
			(pinfunction "GND")
			(pintype "passive")
		)
		(pad "52" smd rect
			(at 3.499 -3.773 270)
			(size 0.3 1.55)
			(layers "B.Cu" "B.Mask" "B.Paste")
			(net 825 "/M.2/~{CLKREQ_M}")
			(pinfunction "~{CLKREQ}")
			(pintype "output")
		)
		(pad "53" smd rect
			(at 3.749 3.775 270)
			(size 0.3 1.55)
			(layers "B.Cu" "B.Mask" "B.Paste")
			(net 584 "/M.2/PCIe_{C5x4}.CLK+")
			(pinfunction "REFCLK_N")
			(pintype "input")
		)
		(pad "54" smd rect
			(at 3.999 -3.773 270)
			(size 0.3 1.55)
			(layers "B.Cu" "B.Mask" "B.Paste")
			(net 826 "/M.2/~{PEWAKE_M}")
			(pinfunction "~{PEWAKE}")
			(pintype "input")
		)
		(pad "55" smd rect
			(at 4.248 3.775 270)
			(size 0.3 1.55)
			(layers "B.Cu" "B.Mask" "B.Paste")
			(net 592 "/M.2/PCIe_{C5x4}.CLK-")
			(pinfunction "REFCLK_P")
			(pintype "input")
		)
		(pad "56" smd rect
			(at 4.498 -3.773 270)
			(size 0.3 1.55)
			(layers "B.Cu" "B.Mask" "B.Paste")
			(net 239 "unconnected-(J13-NC-Pad56)")
			(pinfunction "NC")
			(pintype "no_connect")
		)
		(pad "57" smd rect
			(at 4.748 3.775 270)
			(size 0.3 1.55)
			(layers "B.Cu" "B.Mask" "B.Paste")
			(net 1 "GND")
			(pinfunction "GND")
			(pintype "passive")
		)
		(pad "58" smd rect
			(at 4.998 -3.773 270)
			(size 0.3 1.55)
			(layers "B.Cu" "B.Mask" "B.Paste")
			(net 220 "unconnected-(J13-NC-Pad58)")
			(pinfunction "NC")
			(pintype "no_connect")
		)
		(pad "67" smd rect
			(at 7.248 3.775 270)
			(size 0.3 1.55)
			(layers "B.Cu" "B.Mask" "B.Paste")
			(net 231 "unconnected-(J13-NC-Pad67)")
			(pinfunction "NC")
			(pintype "no_connect")
		)
		(pad "68" smd rect
			(at 7.498 -3.773 270)
			(size 0.3 1.55)
			(layers "B.Cu" "B.Mask" "B.Paste")
			(net 224 "/M.2/M2_M_SUSCLK")
			(pinfunction "SUSCLK")
			(pintype "input")
		)
		(pad "69" smd rect
			(at 7.748 3.775 270)
			(size 0.3 1.55)
			(layers "B.Cu" "B.Mask" "B.Paste")
			(net 221 "unconnected-(J13-NC-Pad69)")
			(pinfunction "NC")
			(pintype "no_connect")
		)
		(pad "70" smd rect
			(at 7.998 -3.773 270)
			(size 0.3 1.55)
			(layers "B.Cu" "B.Mask" "B.Paste")
			(net 14 "/M.2/3V3_M2")
			(pinfunction "3V3")
			(pintype "passive")
		)
		(pad "71" smd rect
			(at 8.247 3.775 270)
			(size 0.3 1.55)
			(layers "B.Cu" "B.Mask" "B.Paste")
			(net 1 "GND")
			(pinfunction "GND")
			(pintype "passive")
		)
		(pad "72" smd rect
			(at 8.497 -3.773 270)
			(size 0.3 1.55)
			(layers "B.Cu" "B.Mask" "B.Paste")
			(net 14 "/M.2/3V3_M2")
			(pinfunction "3V3")
			(pintype "passive")
		)
		(pad "73" smd rect
			(at 8.747 3.775 270)
			(size 0.3 1.55)
			(layers "B.Cu" "B.Mask" "B.Paste")
			(net 1 "GND")
			(pinfunction "GND")
			(pintype "passive")
		)
		(pad "74" smd rect
			(at 8.997 -3.773 270)
			(size 0.3 1.55)
			(layers "B.Cu" "B.Mask" "B.Paste")
			(net 14 "/M.2/3V3_M2")
			(pinfunction "3V3")
			(pintype "passive")
		)
		(pad "75" smd rect
			(at 9.247 3.775 270)
			(size 0.3 1.55)
			(layers "B.Cu" "B.Mask" "B.Paste")
			(net 1 "GND")
			(pinfunction "GND")
			(pintype "passive")
		)
		(pad "MP1" smd rect
			(at -10.352 3 270)
			(size 1.2 2.75)
			(layers "B.Cu" "B.Mask" "B.Paste")
			(net 1 "GND")
			(pinfunction "MP")
			(pintype "passive")
		)
		(pad "MP2" smd rect
			(at 10.349 3 270)
			(size 1.2 2.75)
			(layers "B.Cu" "B.Mask" "B.Paste")
			(net 1 "GND")
			(pinfunction "MP")
			(pintype "passive")
		)
	)
)
